(kicad_pcb
	(version 20260206)
	(generator "pcbnew")
	(generator_version "10.0")
	(general
		(thickness 1.6)
		(legacy_teardrops no)
	)
	(paper "A4")
	(title_block
		(title "pdpb — Lightning_PDPB_BRD.brd")
		(comment 1 "Lightning (Wiwynn / Facebook NVMe JBOF) / footprints 564-571 of 1140")
	)
	(layers
		(0 "F.Cu" signal "TOP")
		(4 "In1.Cu" signal "L2GND")
		(6 "In2.Cu" signal "L3")
		(8 "In3.Cu" signal "L4VCC")
		(10 "In4.Cu" signal "L5VCC")
		(12 "In5.Cu" signal "L6")
		(14 "In6.Cu" signal "L7GND")
		(2 "B.Cu" signal "BOTTOM")
		(9 "F.Adhes" user "F.Adhesive")
		(11 "B.Adhes" user "B.Adhesive")
		(13 "F.Paste" user "Package Geometry/Pastemask Top")
		(15 "B.Paste" user "Package Geometry/Pastemask Bottom")
		(5 "F.SilkS" user "Ref Des/Silkscreen Top")
		(7 "B.SilkS" user "Ref Des/Silkscreen Bottom")
		(1 "F.Mask" user "Board Geometry/Soldermask Top")
		(3 "B.Mask" user "Board Geometry/Soldermask Bottom")
		(17 "Dwgs.User" user "User.Drawings")
		(19 "Cmts.User" user "User.Comments")
		(21 "Eco1.User" user "User.Eco1")
		(23 "Eco2.User" user "User.Eco2")
		(25 "Edge.Cuts" user "Board Geometry/Outline")
		(27 "Margin" user)
		(31 "F.CrtYd" user "Package Geometry/Place Bound Top")
		(29 "B.CrtYd" user "Package Geometry/Place Bound Bottom")
		(35 "F.Fab" user "Ref Des/Assembly Top")
		(33 "B.Fab" user "Ref Des/Assembly Bottom")
	)
	(footprint ""
		(layer "F.Cu")
		(at 227.203 -240.913158 90)
		(property "Reference" "U199"
			(at 0 0 90)
			(layer "F.SilkS")
			(hide yes)
			(effects
				(font
					(size 1.27 1.27)
				)
			)
		)
		(property "Value" "SN74LVC1G08DCKR-GP"
			(at -2.3368 -8.6868 90)
			(unlocked yes)
			(layer "F.Fab")
			(hide yes)
			(effects
				(font
					(size 1.016 1.016)
					(thickness 0.1524)
				)
			)
		)
		(property "Device Type" "SC70-5H44"
			(at -2.3114 -10.414 90)
			(unlocked yes)
			(layer "F.Fab")
			(hide yes)
			(effects
				(font
					(size 1.016 1.016)
					(thickness 0.1524)
				)
			)
		)
		(duplicate_pad_numbers_are_jumpers no)
		(fp_line
			(start 1.3843 -1.8034)
			(end 1.3843 -1.1176)
			(stroke
				(width 0.3302)
				(type default)
			)
			(layer "F.SilkS")
		)
		(fp_line
			(start 0.6604 -1.8034)
			(end 1.3843 -1.8034)
			(stroke
				(width 0.3302)
				(type default)
			)
			(layer "F.SilkS")
		)
		(fp_line
			(start 1.27 -1.7018)
			(end 1.27 1.7018)
			(stroke
				(width 0.1524)
				(type default)
			)
			(layer "F.SilkS")
		)
		(fp_line
			(start -1.27 -1.7018)
			(end 1.27 -1.7018)
			(stroke
				(width 0.1524)
				(type default)
			)
			(layer "F.SilkS")
		)
		(fp_line
			(start 1.27 1.7018)
			(end -1.27 1.7018)
			(stroke
				(width 0.1524)
				(type default)
			)
			(layer "F.SilkS")
		)
		(fp_line
			(start -1.27 1.7018)
			(end -1.27 -1.7018)
			(stroke
				(width 0.1524)
				(type default)
			)
			(layer "F.SilkS")
		)
		(fp_rect
			(start -1.524 1.9558)
			(end 1.524 -1.9558)
			(stroke
				(width 0)
				(type default)
			)
			(fill no)
			(layer "F.CrtYd")
		)
		(fp_poly
			(pts
				(xy -1.524 -1.9558) (xy 1.524 -1.9558) (xy 1.524 1.9558) (xy -1.524 1.9558)
			)
			(stroke
				(width 0)
				(type default)
			)
			(fill no)
			(layer "F.Fab")
		)
		(pad "1" smd rect
			(at 0.65024 -0.8255 90)
			(size 0.4064 1.2192)
			(layers "F.Cu" "F.Mask" "F.Paste")
			(net "SSD2_CLK0_OE_MOS_N")
		)
		(pad "2" smd rect
			(at 0 -0.8255 90)
			(size 0.4064 1.2192)
			(layers "F.Cu" "F.Mask" "F.Paste")
			(net "ATTN_LED_DR2_N")
		)
		(pad "3" smd rect
			(at -0.65024 -0.8255 90)
			(size 0.4064 1.2192)
			(layers "F.Cu" "F.Mask" "F.Paste")
			(net "GND")
		)
		(pad "4" smd rect
			(at -0.65024 0.8255 90)
			(size 0.4064 1.2192)
			(layers "F.Cu" "F.Mask" "F.Paste")
			(net "ATTN_LED_DR2_AND")
		)
		(pad "5" smd rect
			(at 0.65024 0.8255 90)
			(size 0.4064 1.2192)
			(layers "F.Cu" "F.Mask" "F.Paste")
			(net "P3V3")
		)
	)
	(footprint ""
		(layer "F.Cu")
		(at 226.036886 -247.804178 180)
		(property "Reference" "R9931"
			(at 0 0 180)
			(layer "F.SilkS")
			(hide yes)
			(effects
				(font
					(size 1.27 1.27)
				)
			)
		)
		(property "Value" "4K7R2J-2-GP"
			(at 0.064008 -3.993896 180)
			(unlocked yes)
			(layer "F.Fab")
			(hide yes)
			(effects
				(font
					(size 1.016 1.016)
					(thickness 0.1524)
				)
			)
		)
		(property "Device Type" "R402H16"
			(at 0.064008 -5.517896 180)
			(unlocked yes)
			(layer "F.Fab")
			(hide yes)
			(effects
				(font
					(size 1.016 1.016)
					(thickness 0.1524)
				)
			)
		)
		(duplicate_pad_numbers_are_jumpers no)
		(fp_line
			(start 0.508 -0.9398)
			(end -0.508 -0.9398)
			(stroke
				(width 0.1524)
				(type default)
			)
			(layer "F.SilkS")
		)
		(fp_line
			(start -0.508 -0.9398)
			(end -0.508 0.9398)
			(stroke
				(width 0.1524)
				(type default)
			)
			(layer "F.SilkS")
		)
		(fp_rect
			(start -0.508 0.9398)
			(end 0.508 -0.9398)
			(stroke
				(width 0)
				(type default)
			)
			(fill no)
			(layer "F.CrtYd")
		)
		(fp_rect
			(start -0.508 0.9398)
			(end 0.508 -0.9398)
			(stroke
				(width 0)
				(type default)
			)
			(fill no)
			(layer "F.Fab")
		)
		(pad "1" smd custom
			(at 0 -0.4445 180)
			(size 0.1397 0.1397)
			(layers "F.Cu" "F.Mask" "F.Paste")
			(net "P3V3")
			(options
				(clearance outline)
				(anchor circle)
			)
			(primitives
				(gr_poly
					(pts
						(arc
							(start -0.1778 -0.2794)
							(mid -0.249642 -0.249642)
							(end -0.2794 -0.1778)
						)
						(arc
							(start -0.2794 0.1778)
							(mid -0.249642 0.249642)
							(end -0.1778 0.2794)
						)
						(arc
							(start 0.1778 0.2794)
							(mid 0.249642 0.249642)
							(end 0.2794 0.1778)
						)
						(arc
							(start 0.2794 -0.1778)
							(mid 0.249642 -0.249642)
							(end 0.1778 -0.2794)
						)
					)
					(width 0)
					(fill yes)
				)
			)
		)
		(pad "2" smd custom
			(at 0 0.4445 180)
			(size 0.1397 0.1397)
			(layers "F.Cu" "F.Mask" "F.Paste")
			(net "ATTN_LED_DR2_MOS_N")
			(options
				(clearance outline)
				(anchor circle)
			)
			(primitives
				(gr_poly
					(pts
						(arc
							(start -0.1778 -0.2794)
							(mid -0.249642 -0.249642)
							(end -0.2794 -0.1778)
						)
						(arc
							(start -0.2794 0.1778)
							(mid -0.249642 0.249642)
							(end -0.1778 0.2794)
						)
						(arc
							(start 0.1778 0.2794)
							(mid 0.249642 0.249642)
							(end 0.2794 0.1778)
						)
						(arc
							(start 0.2794 -0.1778)
							(mid 0.249642 -0.249642)
							(end 0.1778 -0.2794)
						)
					)
					(width 0)
					(fill yes)
				)
			)
		)
	)
	(footprint ""
		(layer "F.Cu")
		(at 49.276 -247.396 -90)
		(property "Reference" "R9464"
			(at 0 0 270)
			(layer "F.SilkS")
			(hide yes)
			(effects
				(font
					(size 1.27 1.27)
				)
			)
		)
		(property "Value" "100R2J-2-GP"
			(at 0.064008 -3.993896 270)
			(unlocked yes)
			(layer "F.Fab")
			(hide yes)
			(effects
				(font
					(size 1.016 1.016)
					(thickness 0.1524)
				)
			)
		)
		(property "Device Type" "R402H14"
			(at 0.064008 -5.517896 270)
			(unlocked yes)
			(layer "F.Fab")
			(hide yes)
			(effects
				(font
					(size 1.016 1.016)
					(thickness 0.1524)
				)
			)
		)
		(duplicate_pad_numbers_are_jumpers no)
		(fp_line
			(start -0.508 -0.9398)
			(end -0.508 0.9398)
			(stroke
				(width 0.1524)
				(type default)
			)
			(layer "F.SilkS")
		)
		(fp_line
			(start 0.508 -0.9398)
			(end -0.508 -0.9398)
			(stroke
				(width 0.1524)
				(type default)
			)
			(layer "F.SilkS")
		)
		(fp_rect
			(start -0.508 0.9398)
			(end 0.508 -0.9398)
			(stroke
				(width 0)
				(type default)
			)
			(fill no)
			(layer "F.CrtYd")
		)
		(fp_rect
			(start -0.508 0.9398)
			(end 0.508 -0.9398)
			(stroke
				(width 0)
				(type default)
			)
			(fill no)
			(layer "F.Fab")
		)
		(pad "1" smd custom
			(at 0 -0.4445 270)
			(size 0.1397 0.1397)
			(layers "F.Cu" "F.Mask" "F.Paste")
			(net "P3V3")
			(options
				(clearance outline)
				(anchor circle)
			)
			(primitives
				(gr_poly
					(pts
						(arc
							(start -0.1778 -0.2794)
							(mid -0.249642 -0.249642)
							(end -0.2794 -0.1778)
						)
						(arc
							(start -0.2794 0.1778)
							(mid -0.249642 0.249642)
							(end -0.1778 0.2794)
						)
						(arc
							(start 0.1778 0.2794)
							(mid 0.249642 0.249642)
							(end 0.2794 0.1778)
						)
						(arc
							(start 0.2794 -0.1778)
							(mid 0.249642 -0.249642)
							(end 0.1778 -0.2794)
						)
					)
					(width 0)
					(fill yes)
				)
			)
		)
		(pad "2" smd custom
			(at 0 0.4445 270)
			(size 0.1397 0.1397)
			(layers "F.Cu" "F.Mask" "F.Paste")
			(net "DRV_ACT_7")
			(options
				(clearance outline)
				(anchor circle)
			)
			(primitives
				(gr_poly
					(pts
						(arc
							(start -0.1778 -0.2794)
							(mid -0.249642 -0.249642)
							(end -0.2794 -0.1778)
						)
						(arc
							(start -0.2794 0.1778)
							(mid -0.249642 0.249642)
							(end -0.1778 0.2794)
						)
						(arc
							(start 0.1778 0.2794)
							(mid 0.249642 0.249642)
							(end 0.2794 0.1778)
						)
						(arc
							(start 0.2794 -0.1778)
							(mid 0.249642 -0.249642)
							(end 0.1778 -0.2794)
						)
					)
					(width 0)
					(fill yes)
				)
			)
		)
	)
	(footprint ""
		(layer "F.Cu")
		(at 19.2278 -412.496 180)
		(property "Reference" "R9241"
			(at 0 0 180)
			(layer "F.SilkS")
			(hide yes)
			(effects
				(font
					(size 1.27 1.27)
				)
			)
		)
		(property "Value" "2R2010F-GP"
			(at 0.0762 -4.5466 180)
			(unlocked yes)
			(layer "F.Fab")
			(hide yes)
			(effects
				(font
					(size 1.016 1.016)
					(thickness 0.1524)
				)
			)
		)
		(property "Device Type" "R2010H26"
			(at 0.0762 -6.1468 180)
			(unlocked yes)
			(layer "F.Fab")
			(hide yes)
			(effects
				(font
					(size 1.016 1.016)
					(thickness 0.1524)
				)
			)
		)
		(duplicate_pad_numbers_are_jumpers no)
		(fp_line
			(start 3.302 1.651)
			(end 3.302 -1.651)
			(stroke
				(width 0.1524)
				(type default)
			)
			(layer "F.SilkS")
		)
		(fp_line
			(start 3.302 -1.651)
			(end -3.302 -1.651)
			(stroke
				(width 0.1524)
				(type default)
			)
			(layer "F.SilkS")
		)
		(fp_line
			(start -3.302 1.651)
			(end 3.302 1.651)
			(stroke
				(width 0.1524)
				(type default)
			)
			(layer "F.SilkS")
		)
		(fp_line
			(start -3.302 -1.651)
			(end -3.302 1.651)
			(stroke
				(width 0.1524)
				(type default)
			)
			(layer "F.SilkS")
		)
		(fp_rect
			(start -3.3782 1.7272)
			(end 3.3782 -1.7272)
			(stroke
				(width 0)
				(type default)
			)
			(fill no)
			(layer "F.CrtYd")
		)
		(fp_poly
			(pts
				(xy 3.3782 -1.7272) (xy -3.3782 -1.7272) (xy -3.3782 1.7272) (xy 3.3782 1.7272)
			)
			(stroke
				(width 0)
				(type default)
			)
			(fill no)
			(layer "F.Fab")
		)
		(pad "1" smd rect
			(at -2.3495 0 180)
			(size 1.143 2.794)
			(layers "F.Cu" "F.Mask" "F.Paste")
			(net "P12V_SSD10")
		)
		(pad "2" smd rect
			(at 2.3495 0 180)
			(size 1.143 2.794)
			(layers "F.Cu" "F.Mask" "F.Paste")
			(net "12V_PRECH_SSD10")
		)
	)
	(footprint ""
		(layer "F.Cu")
		(at 33.8328 -495.9858)
		(property "Reference" "PC1208"
			(at 0 0 0)
			(layer "F.SilkS")
			(hide yes)
			(effects
				(font
					(size 1.27 1.27)
				)
			)
		)
		(property "Value" "SCD01U50V2KX-1GP"
			(at 1.1811 -2.7051 0)
			(unlocked yes)
			(layer "F.Fab")
			(hide yes)
			(effects
				(font
					(size 1.016 1.016)
					(thickness 0.1524)
				)
			)
		)
		(property "Device Type" "C402H22"
			(at 1.1811 -4.2291 0)
			(unlocked yes)
			(layer "F.Fab")
			(hide yes)
			(effects
				(font
					(size 1.016 1.016)
					(thickness 0.1524)
				)
			)
		)
		(duplicate_pad_numbers_are_jumpers no)
		(fp_rect
			(start -0.4318 0.9525)
			(end 0.4318 -0.9525)
			(stroke
				(width 0)
				(type default)
			)
			(fill no)
			(layer "F.CrtYd")
		)
		(fp_rect
			(start -0.4318 0.9525)
			(end 0.4318 -0.9525)
			(stroke
				(width 0)
				(type default)
			)
			(fill no)
			(layer "F.Fab")
		)
		(pad "1" smd custom
			(at 0 -0.4445)
			(size 0.1524 0.1524)
			(layers "F.Cu" "F.Mask" "F.Paste")
			(net "P12V_SSD5")
			(options
				(clearance outline)
				(anchor circle)
			)
			(primitives
				(gr_poly
					(pts
						(arc
							(start 0.3048 -0.2032)
							(mid 0.275042 -0.275042)
							(end 0.2032 -0.3048)
						)
						(arc
							(start -0.2032 -0.3048)
							(mid -0.275042 -0.275042)
							(end -0.3048 -0.2032)
						)
						(arc
							(start -0.3048 0.2032)
							(mid -0.275042 0.275042)
							(end -0.2032 0.3048)
						)
						(arc
							(start 0.2032 0.3048)
							(mid 0.275042 0.275042)
							(end 0.3048 0.2032)
						)
					)
					(width 0)
					(fill yes)
				)
			)
		)
		(pad "2" smd custom
			(at 0 0.4445)
			(size 0.1524 0.1524)
			(layers "F.Cu" "F.Mask" "F.Paste")
			(net "GND")
			(options
				(clearance outline)
				(anchor circle)
			)
			(primitives
				(gr_poly
					(pts
						(arc
							(start 0.3048 -0.2032)
							(mid 0.275042 -0.275042)
							(end 0.2032 -0.3048)
						)
						(arc
							(start -0.2032 -0.3048)
							(mid -0.275042 -0.275042)
							(end -0.3048 -0.2032)
						)
						(arc
							(start -0.3048 0.2032)
							(mid -0.275042 0.275042)
							(end -0.2032 0.3048)
						)
						(arc
							(start 0.2032 0.3048)
							(mid 0.275042 0.275042)
							(end 0.3048 0.2032)
						)
					)
					(width 0)
					(fill yes)
				)
			)
		)
	)
	(footprint ""
		(layer "F.Cu")
		(at 30.99435 -145.12925)
		(property "Reference" "SR1137"
			(at 0 0 0)
			(layer "F.SilkS")
			(hide yes)
			(effects
				(font
					(size 1.27 1.27)
				)
			)
		)
		(property "Value" "4K7R2F-GP"
			(at 0.064008 -3.993896 0)
			(unlocked yes)
			(layer "F.Fab")
			(hide yes)
			(effects
				(font
					(size 1.016 1.016)
					(thickness 0.1524)
				)
			)
		)
		(property "Device Type" "R402H16"
			(at 0.064008 -5.517896 0)
			(unlocked yes)
			(layer "F.Fab")
			(hide yes)
			(effects
				(font
					(size 1.016 1.016)
					(thickness 0.1524)
				)
			)
		)
		(duplicate_pad_numbers_are_jumpers no)
		(fp_line
			(start -0.508 -0.9398)
			(end -0.508 0.9398)
			(stroke
				(width 0.1524)
				(type default)
			)
			(layer "F.SilkS")
		)
		(fp_line
			(start 0.508 -0.9398)
			(end -0.508 -0.9398)
			(stroke
				(width 0.1524)
				(type default)
			)
			(layer "F.SilkS")
		)
		(fp_rect
			(start -0.508 0.9398)
			(end 0.508 -0.9398)
			(stroke
				(width 0)
				(type default)
			)
			(fill no)
			(layer "F.CrtYd")
		)
		(fp_rect
			(start -0.508 0.9398)
			(end 0.508 -0.9398)
			(stroke
				(width 0)
				(type default)
			)
			(fill no)
			(layer "F.Fab")
		)
		(pad "1" smd custom
			(at 0 -0.4445)
			(size 0.1397 0.1397)
			(layers "F.Cu" "F.Mask" "F.Paste")
			(net "P3V3")
			(options
				(clearance outline)
				(anchor circle)
			)
			(primitives
				(gr_poly
					(pts
						(arc
							(start -0.1778 -0.2794)
							(mid -0.249642 -0.249642)
							(end -0.2794 -0.1778)
						)
						(arc
							(start -0.2794 0.1778)
							(mid -0.249642 0.249642)
							(end -0.1778 0.2794)
						)
						(arc
							(start 0.1778 0.2794)
							(mid 0.249642 0.249642)
							(end 0.2794 0.1778)
						)
						(arc
							(start 0.2794 -0.1778)
							(mid 0.249642 -0.249642)
							(end 0.1778 -0.2794)
						)
					)
					(width 0)
					(fill yes)
				)
			)
		)
		(pad "2" smd custom
			(at 0 0.4445)
			(size 0.1397 0.1397)
			(layers "F.Cu" "F.Mask" "F.Paste")
			(net "SSD8_CLK0_OE_MOS_N")
			(options
				(clearance outline)
				(anchor circle)
			)
			(primitives
				(gr_poly
					(pts
						(arc
							(start -0.1778 -0.2794)
							(mid -0.249642 -0.249642)
							(end -0.2794 -0.1778)
						)
						(arc
							(start -0.2794 0.1778)
							(mid -0.249642 0.249642)
							(end -0.1778 0.2794)
						)
						(arc
							(start 0.1778 0.2794)
							(mid 0.249642 0.249642)
							(end 0.2794 0.1778)
						)
						(arc
							(start 0.2794 -0.1778)
							(mid 0.249642 -0.249642)
							(end 0.1778 -0.2794)
						)
					)
					(width 0)
					(fill yes)
				)
			)
		)
	)
	(footprint ""
		(layer "F.Cu")
		(at 37.0332 -291.7444)
		(property "Reference" "PC1248"
			(at 0 0 0)
			(layer "F.SilkS")
			(hide yes)
			(effects
				(font
					(size 1.27 1.27)
				)
			)
		)
		(property "Value" "SCD01U50V2KX-1GP"
			(at 1.1811 -2.7051 0)
			(unlocked yes)
			(layer "F.Fab")
			(hide yes)
			(effects
				(font
					(size 1.016 1.016)
					(thickness 0.1524)
				)
			)
		)
		(property "Device Type" "C402H22"
			(at 1.1811 -4.2291 0)
			(unlocked yes)
			(layer "F.Fab")
			(hide yes)
			(effects
				(font
					(size 1.016 1.016)
					(thickness 0.1524)
				)
			)
		)
		(duplicate_pad_numbers_are_jumpers no)
		(fp_rect
			(start -0.4318 0.9525)
			(end 0.4318 -0.9525)
			(stroke
				(width 0)
				(type default)
			)
			(fill no)
			(layer "F.CrtYd")
		)
		(fp_rect
			(start -0.4318 0.9525)
			(end 0.4318 -0.9525)
			(stroke
				(width 0)
				(type default)
			)
			(fill no)
			(layer "F.Fab")
		)
		(pad "1" smd custom
			(at 0 -0.4445)
			(size 0.1524 0.1524)
			(layers "F.Cu" "F.Mask" "F.Paste")
			(net "P12V_SSD7")
			(options
				(clearance outline)
				(anchor circle)
			)
			(primitives
				(gr_poly
					(pts
						(arc
							(start 0.3048 -0.2032)
							(mid 0.275042 -0.275042)
							(end 0.2032 -0.3048)
						)
						(arc
							(start -0.2032 -0.3048)
							(mid -0.275042 -0.275042)
							(end -0.3048 -0.2032)
						)
						(arc
							(start -0.3048 0.2032)
							(mid -0.275042 0.275042)
							(end -0.2032 0.3048)
						)
						(arc
							(start 0.2032 0.3048)
							(mid 0.275042 0.275042)
							(end 0.3048 0.2032)
						)
					)
					(width 0)
					(fill yes)
				)
			)
		)
		(pad "2" smd custom
			(at 0 0.4445)
			(size 0.1524 0.1524)
			(layers "F.Cu" "F.Mask" "F.Paste")
			(net "GND")
			(options
				(clearance outline)
				(anchor circle)
			)
			(primitives
				(gr_poly
					(pts
						(arc
							(start 0.3048 -0.2032)
							(mid 0.275042 -0.275042)
							(end 0.2032 -0.3048)
						)
						(arc
							(start -0.2032 -0.3048)
							(mid -0.275042 -0.275042)
							(end -0.3048 -0.2032)
						)
						(arc
							(start -0.3048 0.2032)
							(mid -0.275042 0.275042)
							(end -0.2032 0.3048)
						)
						(arc
							(start 0.2032 0.3048)
							(mid 0.275042 0.275042)
							(end 0.3048 0.2032)
						)
					)
					(width 0)
					(fill yes)
				)
			)
		)
	)
	(footprint ""
		(layer "F.Cu")
		(at 94.488 -312.801 180)
		(property "Reference" "C8851"
			(at 0 0 180)
			(layer "F.SilkS")
			(hide yes)
			(effects
				(font
					(size 1.27 1.27)
				)
			)
		)
		(property "Value" "SCD1U16V2KX-3GP"
			(at 1.1811 -2.7051 180)
			(unlocked yes)
			(layer "F.Fab")
			(hide yes)
			(effects
				(font
					(size 1.016 1.016)
					(thickness 0.1524)
				)
			)
		)
		(property "Device Type" "C402H22"
			(at 1.1811 -4.2291 180)
			(unlocked yes)
			(layer "F.Fab")
			(hide yes)
			(effects
				(font
					(size 1.016 1.016)
					(thickness 0.1524)
				)
			)
		)
		(duplicate_pad_numbers_are_jumpers no)
		(fp_rect
			(start -0.4318 0.9525)
			(end 0.4318 -0.9525)
			(stroke
				(width 0)
				(type default)
			)
			(fill no)
			(layer "F.CrtYd")
		)
		(fp_rect
			(start -0.4318 0.9525)
			(end 0.4318 -0.9525)
			(stroke
				(width 0)
				(type default)
			)
			(fill no)
			(layer "F.Fab")
		)
		(pad "1" smd custom
			(at 0 -0.4445 180)
			(size 0.1524 0.1524)
			(layers "F.Cu" "F.Mask" "F.Paste")
			(net "VDD_IO_2")
			(options
				(clearance outline)
				(anchor circle)
			)
			(primitives
				(gr_poly
					(pts
						(arc
							(start 0.3048 -0.2032)
							(mid 0.275042 -0.275042)
							(end 0.2032 -0.3048)
						)
						(arc
							(start -0.2032 -0.3048)
							(mid -0.275042 -0.275042)
							(end -0.3048 -0.2032)
						)
						(arc
							(start -0.3048 0.2032)
							(mid -0.275042 0.275042)
							(end -0.2032 0.3048)
						)
						(arc
							(start 0.2032 0.3048)
							(mid 0.275042 0.275042)
							(end 0.3048 0.2032)
						)
					)
					(width 0)
					(fill yes)
				)
			)
		)
		(pad "2" smd custom
			(at 0 0.4445 180)
			(size 0.1524 0.1524)
			(layers "F.Cu" "F.Mask" "F.Paste")
			(net "GND")
			(options
				(clearance outline)
				(anchor circle)
			)
			(primitives
				(gr_poly
					(pts
						(arc
							(start 0.3048 -0.2032)
							(mid 0.275042 -0.275042)
							(end 0.2032 -0.3048)
						)
						(arc
							(start -0.2032 -0.3048)
							(mid -0.275042 -0.275042)
							(end -0.3048 -0.2032)
						)
						(arc
							(start -0.3048 0.2032)
							(mid -0.275042 0.275042)
							(end -0.2032 0.3048)
						)
						(arc
							(start 0.2032 0.3048)
							(mid 0.275042 0.275042)
							(end 0.3048 0.2032)
						)
					)
					(width 0)
					(fill yes)
				)
			)
		)
	)
)
